(kicad_pcb
	(version 20260206)
	(generator "pcbnew")
	(generator_version "10.0")
	(general
		(thickness 1.6)
		(legacy_teardrops no)
	)
	(paper "A4")
	(title_block
		(title "Bryce Canyon_R.DPB_16317-1_OCP.brd")
		(comment 1 "Bryce Canyon / footprints 290-292 of 2099")
	)
	(layers
		(0 "F.Cu" signal "TOP")
		(4 "In1.Cu" signal "L2GND")
		(6 "In2.Cu" signal "L3")
		(8 "In3.Cu" signal "L4VCC")
		(10 "In4.Cu" signal "L5VCC")
		(12 "In5.Cu" signal "L6")
		(14 "In6.Cu" signal "L7GND")
		(2 "B.Cu" signal "BOTTOM")
		(9 "F.Adhes" user "F.Adhesive")
		(11 "B.Adhes" user "B.Adhesive")
		(13 "F.Paste" user "Package Geometry/Pastemask Top")
		(15 "B.Paste" user "Package Geometry/Pastemask Bottom")
		(5 "F.SilkS" user "Ref Des/Silkscreen Top")
		(7 "B.SilkS" user "Ref Des/Silkscreen Bottom")
		(1 "F.Mask" user "Board Geometry/Soldermask Top")
		(3 "B.Mask" user "Board Geometry/Soldermask Bottom")
		(17 "Dwgs.User" user "User.Drawings")
		(19 "Cmts.User" user "User.Comments")
		(21 "Eco1.User" user "User.Eco1")
		(23 "Eco2.User" user "User.Eco2")
		(25 "Edge.Cuts" user "Board Geometry/Outline")
		(27 "Margin" user)
		(31 "F.CrtYd" user "Package Geometry/Place Bound Top")
		(29 "B.CrtYd" user "Package Geometry/Place Bound Bottom")
		(35 "F.Fab" user "Ref Des/Assembly Top")
		(33 "B.Fab" user "Ref Des/Assembly Bottom")
	)
	(footprint ""
		(layer "F.Cu")
		(at 254.585978 -228.36505 -90)
		(property "Reference" "R116"
			(at 0 0 270)
			(layer "F.SilkS")
			(hide yes)
			(effects
				(font
					(size 1.27 1.27)
				)
			)
		)
		(property "Value" "10KR2F-2-GP"
			(at 0.064008 -3.993896 270)
			(unlocked yes)
			(layer "F.Fab")
			(hide yes)
			(effects
				(font
					(size 1.016 1.016)
					(thickness 0.1524)
				)
			)
		)
		(property "Device Type" "R402H16"
			(at 0.064008 -5.517896 270)
			(unlocked yes)
			(layer "F.Fab")
			(hide yes)
			(effects
				(font
					(size 1.016 1.016)
					(thickness 0.1524)
				)
			)
		)
		(duplicate_pad_numbers_are_jumpers no)
		(fp_line
			(start -0.508 -0.9398)
			(end -0.508 0.9398)
			(stroke
				(width 0.1524)
				(type default)
			)
			(layer "F.SilkS")
		)
		(fp_line
			(start 0.508 -0.9398)
			(end -0.508 -0.9398)
			(stroke
				(width 0.1524)
				(type default)
			)
			(layer "F.SilkS")
		)
		(fp_rect
			(start -0.508 0.9398)
			(end 0.508 -0.9398)
			(stroke
				(width 0)
				(type default)
			)
			(fill no)
			(layer "F.CrtYd")
		)
		(fp_rect
			(start -0.508 0.9398)
			(end 0.508 -0.9398)
			(stroke
				(width 0)
				(type default)
			)
			(fill no)
			(layer "F.Fab")
		)
		(pad "1" smd custom
			(at 0 -0.4445 270)
			(size 0.1397 0.1397)
			(layers "F.Cu" "F.Mask" "F.Paste")
			(net "P5V_B_1_SENSE")
			(options
				(clearance outline)
				(anchor circle)
			)
			(primitives
				(gr_poly
					(pts
						(arc
							(start -0.1778 -0.2794)
							(mid -0.249642 -0.249642)
							(end -0.2794 -0.1778)
						)
						(arc
							(start -0.2794 0.1778)
							(mid -0.249642 0.249642)
							(end -0.1778 0.2794)
						)
						(arc
							(start 0.1778 0.2794)
							(mid 0.249642 0.249642)
							(end 0.2794 0.1778)
						)
						(arc
							(start 0.2794 -0.1778)
							(mid 0.249642 -0.249642)
							(end 0.1778 -0.2794)
						)
					)
					(width 0)
					(fill yes)
				)
			)
		)
		(pad "2" smd custom
			(at 0 0.4445 270)
			(size 0.1397 0.1397)
			(layers "F.Cu" "F.Mask" "F.Paste")
			(net "GND")
			(options
				(clearance outline)
				(anchor circle)
			)
			(primitives
				(gr_poly
					(pts
						(arc
							(start -0.1778 -0.2794)
							(mid -0.249642 -0.249642)
							(end -0.2794 -0.1778)
						)
						(arc
							(start -0.2794 0.1778)
							(mid -0.249642 0.249642)
							(end -0.1778 0.2794)
						)
						(arc
							(start 0.1778 0.2794)
							(mid 0.249642 0.249642)
							(end 0.2794 0.1778)
						)
						(arc
							(start 0.2794 -0.1778)
							(mid 0.249642 -0.249642)
							(end 0.1778 -0.2794)
						)
					)
					(width 0)
					(fill yes)
				)
			)
		)
	)
	(footprint ""
		(layer "F.Cu")
		(at 83.82 -256.286 180)
		(property "Reference" "Q6"
			(at 0 0 180)
			(layer "F.SilkS")
			(hide yes)
			(effects
				(font
					(size 1.27 1.27)
				)
			)
		)
		(property "Value" "AO4406AL-GP"
			(at -3.707384 -1.5367 180)
			(unlocked yes)
			(layer "F.Fab")
			(hide yes)
			(effects
				(font
					(size 1.016 1.016)
					(thickness 0.1524)
				)
			)
		)
		(property "Device Type" "SOIC8H69"
			(at -3.707384 -3.0607 180)
			(unlocked yes)
			(layer "F.Fab")
			(hide yes)
			(effects
				(font
					(size 1.016 1.016)
					(thickness 0.1524)
				)
			)
		)
		(duplicate_pad_numbers_are_jumpers no)
		(fp_line
			(start 2.1336 1.4224)
			(end 2.1336 -1.4224)
			(stroke
				(width 0.1524)
				(type default)
			)
			(layer "F.SilkS")
		)
		(fp_line
			(start 2.1336 -1.4224)
			(end -2.7432 -1.4224)
			(stroke
				(width 0.1524)
				(type default)
			)
			(layer "F.SilkS")
		)
		(fp_line
			(start -2.1844 -0.0508)
			(end -2.7178 0.508)
			(stroke
				(width 0.1524)
				(type default)
			)
			(layer "F.SilkS")
		)
		(fp_line
			(start -2.6289 3.4417)
			(end -2.6289 1.4732)
			(stroke
				(width 0.381)
				(type default)
			)
			(layer "F.SilkS")
		)
		(fp_line
			(start -2.7178 -0.508)
			(end -2.1844 -0.0508)
			(stroke
				(width 0.1524)
				(type default)
			)
			(layer "F.SilkS")
		)
		(fp_line
			(start -2.7432 1.4224)
			(end 2.1336 1.4224)
			(stroke
				(width 0.1524)
				(type default)
			)
			(layer "F.SilkS")
		)
		(fp_line
			(start -2.7432 1.4224)
			(end -2.6416 1.4224)
			(stroke
				(width 0.1524)
				(type default)
			)
			(layer "F.SilkS")
		)
		(fp_line
			(start -2.7432 -1.4224)
			(end -2.7432 1.4224)
			(stroke
				(width 0.1524)
				(type default)
			)
			(layer "F.SilkS")
		)
		(fp_poly
			(pts
				(xy -2.2098 -1.4224) (xy -2.2098 1.4224) (xy 2.2098 1.4224) (xy 2.2098 -1.4224)
			)
			(stroke
				(width 0)
				(type default)
			)
			(fill yes)
			(layer "F.SilkS")
		)
		(fp_rect
			(start -2.450084 2.999994)
			(end 2.450084 -2.999994)
			(stroke
				(width 0)
				(type default)
			)
			(fill no)
			(layer "F.CrtYd")
		)
		(fp_poly
			(pts
				(xy -2.8194 3.6322) (xy -2.8194 -3.6322) (xy 2.8194 -3.6322) (xy 2.8194 1.18364) (xy 2.450084 1.18364)
				(xy 2.450084 -2.999994) (xy -2.450084 -2.999994) (xy -2.450084 2.999994) (xy 2.450084 2.999994)
				(xy 2.450084 1.18618) (xy 2.8194 1.18618) (xy 2.8194 3.6322)
			)
			(stroke
				(width 0)
				(type default)
			)
			(fill no)
			(layer "F.CrtYd")
		)
		(fp_rect
			(start -2.8194 3.6322)
			(end 2.8194 -3.6322)
			(stroke
				(width 0)
				(type default)
			)
			(fill no)
			(layer "F.Fab")
		)
		(pad "1" smd rect
			(at -1.905 2.54 180)
			(size 0.635 1.651)
			(layers "F.Cu" "F.Mask" "F.Paste")
			(net "P5V_HDD2")
		)
		(pad "2" smd rect
			(at -0.635 2.54 180)
			(size 0.635 1.651)
			(layers "F.Cu" "F.Mask" "F.Paste")
			(net "P5V_HDD2")
		)
		(pad "3" smd rect
			(at 0.635 2.54 180)
			(size 0.635 1.651)
			(layers "F.Cu" "F.Mask" "F.Paste")
			(net "P5V_HDD2")
		)
		(pad "4" smd rect
			(at 1.905 2.54 180)
			(size 0.635 1.651)
			(layers "F.Cu" "F.Mask" "F.Paste")
			(net "SW_HDD_P2")
		)
		(pad "5" smd rect
			(at 1.905 -2.54 180)
			(size 0.635 1.651)
			(layers "F.Cu" "F.Mask" "F.Paste")
			(net "P5V_B_1")
		)
		(pad "6" smd rect
			(at 0.635 -2.54 180)
			(size 0.635 1.651)
			(layers "F.Cu" "F.Mask" "F.Paste")
			(net "P5V_B_1")
		)
		(pad "7" smd rect
			(at -0.635 -2.54 180)
			(size 0.635 1.651)
			(layers "F.Cu" "F.Mask" "F.Paste")
			(net "P5V_B_1")
		)
		(pad "8" smd rect
			(at -1.905 -2.54 180)
			(size 0.635 1.651)
			(layers "F.Cu" "F.Mask" "F.Paste")
			(net "P5V_B_1")
		)
	)
	(footprint ""
		(layer "F.Cu")
		(at 329.819 -152.908 180)
		(property "Reference" "C264"
			(at 0 0 180)
			(layer "F.SilkS")
			(hide yes)
			(effects
				(font
					(size 1.27 1.27)
				)
			)
		)
		(property "Value" "SC1U16V3KX-5GP"
			(at 0 -2.8194 180)
			(unlocked yes)
			(layer "F.Fab")
			(hide yes)
			(effects
				(font
					(size 1.016 1.016)
					(thickness 0.1524)
				)
			)
		)
		(property "Device Type" "C603H36"
			(at 0 -4.3434 180)
			(unlocked yes)
			(layer "F.Fab")
			(hide yes)
			(effects
				(font
					(size 1.016 1.016)
					(thickness 0.1524)
				)
			)
		)
		(duplicate_pad_numbers_are_jumpers no)
		(fp_line
			(start 0.508 0)
			(end -0.508 0)
			(stroke
				(width 0.2032)
				(type default)
			)
			(layer "F.SilkS")
		)
		(fp_rect
			(start -0.5842 1.3335)
			(end 0.5842 -1.3335)
			(stroke
				(width 0)
				(type default)
			)
			(fill no)
			(layer "F.CrtYd")
		)
		(fp_rect
			(start -0.5842 1.3335)
			(end 0.5842 -1.3335)
			(stroke
				(width 0)
				(type default)
			)
			(fill no)
			(layer "F.Fab")
		)
		(pad "1" smd custom
			(at 0 -0.762 180)
			(size 0.2159 0.2159)
			(layers "F.Cu" "F.Mask" "F.Paste")
			(net "P5V_HDD18")
			(options
				(clearance outline)
				(anchor circle)
			)
			(primitives
				(gr_poly
					(pts
						(arc
							(start -0.3302 -0.4318)
							(mid -0.402042 -0.402042)
							(end -0.4318 -0.3302)
						)
						(arc
							(start -0.4318 0.3302)
							(mid -0.402042 0.402042)
							(end -0.3302 0.4318)
						)
						(arc
							(start 0.3302 0.4318)
							(mid 0.402042 0.402042)
							(end 0.4318 0.3302)
						)
						(arc
							(start 0.4318 -0.3302)
							(mid 0.402042 -0.402042)
							(end 0.3302 -0.4318)
						)
					)
					(width 0)
					(fill yes)
				)
			)
		)
		(pad "2" smd custom
			(at 0 0.762 180)
			(size 0.2159 0.2159)
			(layers "F.Cu" "F.Mask" "F.Paste")
			(net "GND")
			(options
				(clearance outline)
				(anchor circle)
			)
			(primitives
				(gr_poly
					(pts
						(arc
							(start -0.3302 -0.4318)
							(mid -0.402042 -0.402042)
							(end -0.4318 -0.3302)
						)
						(arc
							(start -0.4318 0.3302)
							(mid -0.402042 0.402042)
							(end -0.3302 0.4318)
						)
						(arc
							(start 0.3302 0.4318)
							(mid 0.402042 0.402042)
							(end 0.4318 0.3302)
						)
						(arc
							(start 0.4318 -0.3302)
							(mid 0.402042 -0.402042)
							(end 0.3302 -0.4318)
						)
					)
					(width 0)
					(fill yes)
				)
			)
		)
	)
)
